(kicad_pcb
	(version 20260206)
	(generator "pcbnew")
	(generator_version "10.0")
	(general
		(thickness 1.6)
		(legacy_teardrops no)
	)
	(paper "A4")
	(title_block
		(title "Bryce Canyon_R.DPB_16317-1_OCP.brd")
		(comment 1 "Bryce Canyon / footprints 698-703 of 2099")
	)
	(layers
		(0 "F.Cu" signal "TOP")
		(4 "In1.Cu" signal "L2GND")
		(6 "In2.Cu" signal "L3")
		(8 "In3.Cu" signal "L4VCC")
		(10 "In4.Cu" signal "L5VCC")
		(12 "In5.Cu" signal "L6")
		(14 "In6.Cu" signal "L7GND")
		(2 "B.Cu" signal "BOTTOM")
		(9 "F.Adhes" user "F.Adhesive")
		(11 "B.Adhes" user "B.Adhesive")
		(13 "F.Paste" user "Package Geometry/Pastemask Top")
		(15 "B.Paste" user "Package Geometry/Pastemask Bottom")
		(5 "F.SilkS" user "Ref Des/Silkscreen Top")
		(7 "B.SilkS" user "Ref Des/Silkscreen Bottom")
		(1 "F.Mask" user "Board Geometry/Soldermask Top")
		(3 "B.Mask" user "Board Geometry/Soldermask Bottom")
		(17 "Dwgs.User" user "User.Drawings")
		(19 "Cmts.User" user "User.Comments")
		(21 "Eco1.User" user "User.Eco1")
		(23 "Eco2.User" user "User.Eco2")
		(25 "Edge.Cuts" user "Board Geometry/Outline")
		(27 "Margin" user)
		(31 "F.CrtYd" user "Package Geometry/Place Bound Top")
		(29 "B.CrtYd" user "Package Geometry/Place Bound Bottom")
		(35 "F.Fab" user "Ref Des/Assembly Top")
		(33 "B.Fab" user "Ref Des/Assembly Bottom")
	)
	(footprint ""
		(layer "F.Cu")
		(at 215.773 -221.234 -90)
		(property "Reference" "U3"
			(at 0 0 270)
			(layer "F.SilkS")
			(hide yes)
			(effects
				(font
					(size 1.27 1.27)
				)
			)
		)
		(property "Value" "TCA9555PWR-GP"
			(at 0 -6.9342 270)
			(unlocked yes)
			(layer "F.Fab")
			(hide yes)
			(effects
				(font
					(size 1.016 1.016)
					(thickness 0.1524)
				)
			)
		)
		(property "Device Type" "TSOIC24H48"
			(at 0 -8.5852 270)
			(unlocked yes)
			(layer "F.Fab")
			(hide yes)
			(effects
				(font
					(size 1.016 1.016)
					(thickness 0.1524)
				)
			)
		)
		(duplicate_pad_numbers_are_jumpers no)
		(fp_line
			(start -4.2291 3.937)
			(end -4.2291 -1.397)
			(stroke
				(width 0.1524)
				(type default)
			)
			(layer "F.SilkS")
		)
		(fp_line
			(start -4.22656 3.81)
			(end -4.2291 1.397)
			(stroke
				(width 0.508)
				(type default)
			)
			(layer "F.SilkS")
		)
		(fp_line
			(start 3.81 1.397)
			(end -4.2291 1.397)
			(stroke
				(width 0.1524)
				(type default)
			)
			(layer "F.SilkS")
		)
		(fp_line
			(start -3.429 0)
			(end -4.2291 0.8001)
			(stroke
				(width 0.1524)
				(type default)
			)
			(layer "F.SilkS")
		)
		(fp_line
			(start -4.2291 -0.8001)
			(end -3.429 0)
			(stroke
				(width 0.1524)
				(type default)
			)
			(layer "F.SilkS")
		)
		(fp_line
			(start -4.2291 -1.397)
			(end 3.81 -1.397)
			(stroke
				(width 0.1524)
				(type default)
			)
			(layer "F.SilkS")
		)
		(fp_line
			(start 3.81 -1.397)
			(end 3.81 1.397)
			(stroke
				(width 0.1524)
				(type default)
			)
			(layer "F.SilkS")
		)
		(fp_poly
			(pts
				(xy -3.90652 -1.8542) (xy 3.90652 -1.8542) (xy 3.90652 1.8542) (xy -3.90652 1.8542)
			)
			(stroke
				(width 0)
				(type default)
			)
			(fill yes)
			(layer "F.SilkS")
		)
		(fp_poly
			(pts
				(xy -4.2164 3.81) (xy 4.2164 3.81) (xy 4.22656 -3.81) (xy -4.2164 -3.81)
			)
			(stroke
				(width 0)
				(type default)
			)
			(fill no)
			(layer "F.CrtYd")
		)
		(fp_poly
			(pts
				(xy -4.22656 -3.81) (xy 4.22656 -3.81) (xy 4.22656 3.81) (xy -4.22656 3.81)
			)
			(stroke
				(width 0)
				(type default)
			)
			(fill no)
			(layer "F.Fab")
		)
		(pad "1" smd rect
			(at -3.57632 2.8194 270)
			(size 0.3556 1.524)
			(layers "F.Cu" "F.Mask" "F.Paste")
			(net "IO_EXP1_HDD_FAULT_INT_N")
		)
		(pad "2" smd rect
			(at -2.92608 2.8194 270)
			(size 0.3556 1.524)
			(layers "F.Cu" "F.Mask" "F.Paste")
			(net "IO_EXP1_HDD_FAULT_A1")
		)
		(pad "3" smd rect
			(at -2.27584 2.8194 270)
			(size 0.3556 1.524)
			(layers "F.Cu" "F.Mask" "F.Paste")
			(net "IO_EXP1_HDD_FAULT_A2")
		)
		(pad "4" smd rect
			(at -1.6256 2.8194 270)
			(size 0.3556 1.524)
			(layers "F.Cu" "F.Mask" "F.Paste")
			(net "DRIVE_B_0_FLT_LED")
		)
		(pad "5" smd rect
			(at -0.97536 2.8194 270)
			(size 0.3556 1.524)
			(layers "F.Cu" "F.Mask" "F.Paste")
			(net "DRIVE_B_1_FLT_LED")
		)
		(pad "6" smd rect
			(at -0.32512 2.8194 270)
			(size 0.3556 1.524)
			(layers "F.Cu" "F.Mask" "F.Paste")
			(net "DRIVE_B_2_FLT_LED")
		)
		(pad "7" smd rect
			(at 0.32512 2.8194 270)
			(size 0.3556 1.524)
			(layers "F.Cu" "F.Mask" "F.Paste")
			(net "DRIVE_B_3_FLT_LED")
		)
		(pad "8" smd rect
			(at 0.97536 2.8194 270)
			(size 0.3556 1.524)
			(layers "F.Cu" "F.Mask" "F.Paste")
			(net "DRIVE_B_4_FLT_LED")
		)
		(pad "9" smd rect
			(at 1.6256 2.8194 270)
			(size 0.3556 1.524)
			(layers "F.Cu" "F.Mask" "F.Paste")
			(net "DRIVE_B_5_FLT_LED")
		)
		(pad "10" smd rect
			(at 2.27584 2.8194 270)
			(size 0.3556 1.524)
			(layers "F.Cu" "F.Mask" "F.Paste")
			(net "DRIVE_B_6_FLT_LED")
		)
		(pad "11" smd rect
			(at 2.92608 2.8194 270)
			(size 0.3556 1.524)
			(layers "F.Cu" "F.Mask" "F.Paste")
			(net "DRIVE_B_7_FLT_LED")
		)
		(pad "12" smd rect
			(at 3.57632 2.8194 270)
			(size 0.3556 1.524)
			(layers "F.Cu" "F.Mask" "F.Paste")
			(net "GND")
		)
		(pad "13" smd rect
			(at 3.57632 -2.8194 270)
			(size 0.3556 1.524)
			(layers "F.Cu" "F.Mask" "F.Paste")
			(net "DRIVE_B_8_FLT_LED")
		)
		(pad "14" smd rect
			(at 2.92608 -2.8194 270)
			(size 0.3556 1.524)
			(layers "F.Cu" "F.Mask" "F.Paste")
			(net "DRIVE_B_9_FLT_LED")
		)
		(pad "15" smd rect
			(at 2.27584 -2.8194 270)
			(size 0.3556 1.524)
			(layers "F.Cu" "F.Mask" "F.Paste")
			(net "DRIVE_B_10_FLT_LED")
		)
		(pad "16" smd rect
			(at 1.6256 -2.8194 270)
			(size 0.3556 1.524)
			(layers "F.Cu" "F.Mask" "F.Paste")
			(net "DRIVE_B_11_FLT_LED")
		)
		(pad "17" smd rect
			(at 0.97536 -2.8194 270)
			(size 0.3556 1.524)
			(layers "F.Cu" "F.Mask" "F.Paste")
			(net "DRIVE_B_12_FLT_LED")
		)
		(pad "18" smd rect
			(at 0.32512 -2.8194 270)
			(size 0.3556 1.524)
			(layers "F.Cu" "F.Mask" "F.Paste")
			(net "DRIVE_B_13_FLT_LED")
		)
		(pad "19" smd rect
			(at -0.32512 -2.8194 270)
			(size 0.3556 1.524)
			(layers "F.Cu" "F.Mask" "F.Paste")
			(net "DRIVE_B_14_FLT_LED")
		)
		(pad "20" smd rect
			(at -0.97536 -2.8194 270)
			(size 0.3556 1.524)
			(layers "F.Cu" "F.Mask" "F.Paste")
			(net "DRIVE_B_15_FLT_LED")
		)
		(pad "21" smd rect
			(at -1.6256 -2.8194 270)
			(size 0.3556 1.524)
			(layers "F.Cu" "F.Mask" "F.Paste")
			(net "IO_EXP1_HDD_FAULT_A0")
		)
		(pad "22" smd rect
			(at -2.27584 -2.8194 270)
			(size 0.3556 1.524)
			(layers "F.Cu" "F.Mask" "F.Paste")
			(net "IO_EXP1_LED_SCL")
		)
		(pad "23" smd rect
			(at -2.92608 -2.8194 270)
			(size 0.3556 1.524)
			(layers "F.Cu" "F.Mask" "F.Paste")
			(net "IO_EXP1_LED_SDA")
		)
		(pad "24" smd rect
			(at -3.57632 -2.8194 270)
			(size 0.3556 1.524)
			(layers "F.Cu" "F.Mask" "F.Paste")
			(net "P3V3_STBY_B")
		)
	)
	(footprint ""
		(layer "F.Cu")
		(at 161.925 -151.003 90)
		(property "Reference" "R442"
			(at 0 0 90)
			(layer "F.SilkS")
			(hide yes)
			(effects
				(font
					(size 1.27 1.27)
				)
			)
		)
		(property "Value" "220R3F-1-GP"
			(at -0.0254 -2.5146 90)
			(unlocked yes)
			(layer "F.Fab")
			(hide yes)
			(effects
				(font
					(size 1.016 1.016)
					(thickness 0.1524)
				)
			)
		)
		(property "Device Type" "R603H22"
			(at -0.0254 -4.0386 90)
			(unlocked yes)
			(layer "F.Fab")
			(hide yes)
			(effects
				(font
					(size 1.016 1.016)
					(thickness 0.1524)
				)
			)
		)
		(duplicate_pad_numbers_are_jumpers no)
		(fp_line
			(start 0.2032 0)
			(end 0.4826 0)
			(stroke
				(width 0.2032)
				(type default)
			)
			(layer "F.SilkS")
		)
		(fp_line
			(start -0.4826 0)
			(end -0.2032 0)
			(stroke
				(width 0.2032)
				(type default)
			)
			(layer "F.SilkS")
		)
		(fp_rect
			(start -0.5842 1.3335)
			(end 0.5842 -1.3335)
			(stroke
				(width 0)
				(type default)
			)
			(fill no)
			(layer "F.CrtYd")
		)
		(fp_rect
			(start -0.5842 1.3335)
			(end 0.5842 -1.3335)
			(stroke
				(width 0)
				(type default)
			)
			(fill no)
			(layer "F.Fab")
		)
		(pad "1" smd custom
			(at 0 -0.762 90)
			(size 0.2159 0.2159)
			(layers "F.Cu" "F.Mask" "F.Paste")
			(net "HDD_PRSNT_16")
			(options
				(clearance outline)
				(anchor circle)
			)
			(primitives
				(gr_poly
					(pts
						(arc
							(start -0.3302 -0.4318)
							(mid -0.402042 -0.402042)
							(end -0.4318 -0.3302)
						)
						(arc
							(start -0.4318 0.3302)
							(mid -0.402042 0.402042)
							(end -0.3302 0.4318)
						)
						(arc
							(start 0.3302 0.4318)
							(mid 0.402042 0.402042)
							(end 0.4318 0.3302)
						)
						(arc
							(start 0.4318 -0.3302)
							(mid 0.402042 -0.402042)
							(end 0.3302 -0.4318)
						)
					)
					(width 0)
					(fill yes)
				)
			)
		)
		(pad "2" smd custom
			(at 0 0.762 90)
			(size 0.2159 0.2159)
			(layers "F.Cu" "F.Mask" "F.Paste")
			(net "DRIVE_B_16_INS")
			(options
				(clearance outline)
				(anchor circle)
			)
			(primitives
				(gr_poly
					(pts
						(arc
							(start -0.3302 -0.4318)
							(mid -0.402042 -0.402042)
							(end -0.4318 -0.3302)
						)
						(arc
							(start -0.4318 0.3302)
							(mid -0.402042 0.402042)
							(end -0.3302 0.4318)
						)
						(arc
							(start 0.3302 0.4318)
							(mid 0.402042 0.402042)
							(end 0.4318 0.3302)
						)
						(arc
							(start 0.4318 -0.3302)
							(mid 0.402042 -0.402042)
							(end 0.3302 -0.4318)
						)
					)
					(width 0)
					(fill yes)
				)
			)
		)
	)
	(footprint ""
		(layer "F.Cu")
		(at 172.974 -248.158 180)
		(property "Reference" "R250"
			(at 0 0 180)
			(layer "F.SilkS")
			(hide yes)
			(effects
				(font
					(size 1.27 1.27)
				)
			)
		)
		(property "Value" "200KR2F-L-GP"
			(at 0.064008 -3.993896 180)
			(unlocked yes)
			(layer "F.Fab")
			(hide yes)
			(effects
				(font
					(size 1.016 1.016)
					(thickness 0.1524)
				)
			)
		)
		(property "Device Type" "R402H16"
			(at 0.064008 -5.517896 180)
			(unlocked yes)
			(layer "F.Fab")
			(hide yes)
			(effects
				(font
					(size 1.016 1.016)
					(thickness 0.1524)
				)
			)
		)
		(duplicate_pad_numbers_are_jumpers no)
		(fp_line
			(start 0.508 -0.9398)
			(end -0.508 -0.9398)
			(stroke
				(width 0.1524)
				(type default)
			)
			(layer "F.SilkS")
		)
		(fp_line
			(start -0.508 -0.9398)
			(end -0.508 0.9398)
			(stroke
				(width 0.1524)
				(type default)
			)
			(layer "F.SilkS")
		)
		(fp_rect
			(start -0.508 0.9398)
			(end 0.508 -0.9398)
			(stroke
				(width 0)
				(type default)
			)
			(fill no)
			(layer "F.CrtYd")
		)
		(fp_rect
			(start -0.508 0.9398)
			(end 0.508 -0.9398)
			(stroke
				(width 0)
				(type default)
			)
			(fill no)
			(layer "F.Fab")
		)
		(pad "1" smd custom
			(at 0 -0.4445 180)
			(size 0.1397 0.1397)
			(layers "F.Cu" "F.Mask" "F.Paste")
			(net "SW_HDD_R5")
			(options
				(clearance outline)
				(anchor circle)
			)
			(primitives
				(gr_poly
					(pts
						(arc
							(start -0.1778 -0.2794)
							(mid -0.249642 -0.249642)
							(end -0.2794 -0.1778)
						)
						(arc
							(start -0.2794 0.1778)
							(mid -0.249642 0.249642)
							(end -0.1778 0.2794)
						)
						(arc
							(start 0.1778 0.2794)
							(mid 0.249642 0.249642)
							(end 0.2794 0.1778)
						)
						(arc
							(start 0.2794 -0.1778)
							(mid 0.249642 -0.249642)
							(end 0.1778 -0.2794)
						)
					)
					(width 0)
					(fill yes)
				)
			)
		)
		(pad "2" smd custom
			(at 0 0.4445 180)
			(size 0.1397 0.1397)
			(layers "F.Cu" "F.Mask" "F.Paste")
			(net "SW_HDD_N5")
			(options
				(clearance outline)
				(anchor circle)
			)
			(primitives
				(gr_poly
					(pts
						(arc
							(start -0.1778 -0.2794)
							(mid -0.249642 -0.249642)
							(end -0.2794 -0.1778)
						)
						(arc
							(start -0.2794 0.1778)
							(mid -0.249642 0.249642)
							(end -0.1778 0.2794)
						)
						(arc
							(start 0.1778 0.2794)
							(mid 0.249642 0.249642)
							(end 0.2794 0.1778)
						)
						(arc
							(start 0.2794 -0.1778)
							(mid 0.249642 -0.249642)
							(end 0.1778 -0.2794)
						)
					)
					(width 0)
					(fill yes)
				)
			)
		)
	)
	(footprint ""
		(layer "F.Cu")
		(at 338.709 -257.81 -90)
		(property "Reference" "R265"
			(at 0 0 270)
			(layer "F.SilkS")
			(hide yes)
			(effects
				(font
					(size 1.27 1.27)
				)
			)
		)
		(property "Value" "300KR2F-GP"
			(at 0.064008 -3.993896 270)
			(unlocked yes)
			(layer "F.Fab")
			(hide yes)
			(effects
				(font
					(size 1.016 1.016)
					(thickness 0.1524)
				)
			)
		)
		(property "Device Type" "R402H16"
			(at 0.064008 -5.517896 270)
			(unlocked yes)
			(layer "F.Fab")
			(hide yes)
			(effects
				(font
					(size 1.016 1.016)
					(thickness 0.1524)
				)
			)
		)
		(duplicate_pad_numbers_are_jumpers no)
		(fp_line
			(start -0.508 -0.9398)
			(end -0.508 0.9398)
			(stroke
				(width 0.1524)
				(type default)
			)
			(layer "F.SilkS")
		)
		(fp_line
			(start 0.508 -0.9398)
			(end -0.508 -0.9398)
			(stroke
				(width 0.1524)
				(type default)
			)
			(layer "F.SilkS")
		)
		(fp_rect
			(start -0.508 0.9398)
			(end 0.508 -0.9398)
			(stroke
				(width 0)
				(type default)
			)
			(fill no)
			(layer "F.CrtYd")
		)
		(fp_rect
			(start -0.508 0.9398)
			(end 0.508 -0.9398)
			(stroke
				(width 0)
				(type default)
			)
			(fill no)
			(layer "F.Fab")
		)
		(pad "1" smd custom
			(at 0 -0.4445 270)
			(size 0.1397 0.1397)
			(layers "F.Cu" "F.Mask" "F.Paste")
			(net "SW_HDD_N6")
			(options
				(clearance outline)
				(anchor circle)
			)
			(primitives
				(gr_poly
					(pts
						(arc
							(start -0.1778 -0.2794)
							(mid -0.249642 -0.249642)
							(end -0.2794 -0.1778)
						)
						(arc
							(start -0.2794 0.1778)
							(mid -0.249642 0.249642)
							(end -0.1778 0.2794)
						)
						(arc
							(start 0.1778 0.2794)
							(mid 0.249642 0.249642)
							(end 0.2794 0.1778)
						)
						(arc
							(start 0.2794 -0.1778)
							(mid 0.249642 -0.249642)
							(end 0.1778 -0.2794)
						)
					)
					(width 0)
					(fill yes)
				)
			)
		)
		(pad "2" smd custom
			(at 0 0.4445 270)
			(size 0.1397 0.1397)
			(layers "F.Cu" "F.Mask" "F.Paste")
			(net "P12V_B")
			(options
				(clearance outline)
				(anchor circle)
			)
			(primitives
				(gr_poly
					(pts
						(arc
							(start -0.1778 -0.2794)
							(mid -0.249642 -0.249642)
							(end -0.2794 -0.1778)
						)
						(arc
							(start -0.2794 0.1778)
							(mid -0.249642 0.249642)
							(end -0.1778 0.2794)
						)
						(arc
							(start 0.1778 0.2794)
							(mid 0.249642 0.249642)
							(end 0.2794 0.1778)
						)
						(arc
							(start 0.2794 -0.1778)
							(mid 0.249642 -0.249642)
							(end 0.1778 -0.2794)
						)
					)
					(width 0)
					(fill yes)
				)
			)
		)
	)
	(footprint ""
		(layer "F.Cu")
		(at 439.82386 -111.266478 -90)
		(property "Reference" "R1162"
			(at 0 0 270)
			(layer "F.SilkS")
			(hide yes)
			(effects
				(font
					(size 1.27 1.27)
				)
			)
		)
		(property "Value" "3D01R5F-GP"
			(at 0 -8.9535 270)
			(unlocked yes)
			(layer "F.Fab")
			(hide yes)
			(effects
				(font
					(size 1.27 1.016)
					(thickness 0.1524)
				)
			)
		)
		(property "Device Type" "R805H24"
			(at 0 -10.6299 270)
			(unlocked yes)
			(layer "F.Fab")
			(hide yes)
			(effects
				(font
					(size 1.27 1.016)
					(thickness 0.1524)
				)
			)
		)
		(duplicate_pad_numbers_are_jumpers no)
		(fp_line
			(start -0.889 1.7018)
			(end 0.889 1.7018)
			(stroke
				(width 0.1524)
				(type default)
			)
			(layer "F.SilkS")
		)
		(fp_line
			(start 0.889 1.7018)
			(end 0.889 -0.508)
			(stroke
				(width 0.1524)
				(type default)
			)
			(layer "F.SilkS")
		)
		(fp_line
			(start -0.889 0.0762)
			(end -0.889 1.7018)
			(stroke
				(width 0.1524)
				(type default)
			)
			(layer "F.SilkS")
		)
		(fp_line
			(start -0.889 -1.7018)
			(end -0.889 0.2794)
			(stroke
				(width 0.1524)
				(type default)
			)
			(layer "F.SilkS")
		)
		(fp_line
			(start 0.889 -1.7018)
			(end 0.889 -0.381)
			(stroke
				(width 0.1524)
				(type default)
			)
			(layer "F.SilkS")
		)
		(fp_line
			(start 0.889 -1.7018)
			(end -0.889 -1.7018)
			(stroke
				(width 0.1524)
				(type default)
			)
			(layer "F.SilkS")
		)
		(fp_poly
			(pts
				(xy 0.9652 -1.778) (xy 0.9652 1.778) (xy -0.9652 1.778) (xy -0.9652 -1.778)
			)
			(stroke
				(width 0)
				(type default)
			)
			(fill no)
			(layer "F.CrtYd")
		)
		(fp_rect
			(start -0.9652 1.778)
			(end 0.9652 -1.778)
			(stroke
				(width 0)
				(type default)
			)
			(fill no)
			(layer "F.Fab")
		)
		(pad "1" smd rect
			(at 0 -0.9652 270)
			(size 1.397 1.143)
			(layers "F.Cu" "F.Mask" "F.Paste")
			(net "P5V_B_4_SNB")
		)
		(pad "2" smd rect
			(at 0 0.9652 270)
			(size 1.397 1.143)
			(layers "F.Cu" "F.Mask" "F.Paste")
			(net "GND")
		)
	)
	(footprint ""
		(layer "F.Cu")
		(at 46.957996 -360.2355 180)
		(property "Reference" "C365"
			(at 0 0 180)
			(layer "F.SilkS")
			(hide yes)
			(effects
				(font
					(size 1.27 1.27)
				)
			)
		)
		(property "Value" "SCD033U25V2KX-GP"
			(at 1.1811 -2.7051 180)
			(unlocked yes)
			(layer "F.Fab")
			(hide yes)
			(effects
				(font
					(size 1.016 1.016)
					(thickness 0.1524)
				)
			)
		)
		(property "Device Type" "C402H22"
			(at 1.1811 -4.2291 180)
			(unlocked yes)
			(layer "F.Fab")
			(hide yes)
			(effects
				(font
					(size 1.016 1.016)
					(thickness 0.1524)
				)
			)
		)
		(duplicate_pad_numbers_are_jumpers no)
		(fp_rect
			(start -0.4318 0.9525)
			(end 0.4318 -0.9525)
			(stroke
				(width 0)
				(type default)
			)
			(fill no)
			(layer "F.CrtYd")
		)
		(fp_rect
			(start -0.4318 0.9525)
			(end 0.4318 -0.9525)
			(stroke
				(width 0)
				(type default)
			)
			(fill no)
			(layer "F.Fab")
		)
		(pad "1" smd custom
			(at 0 -0.4445 180)
			(size 0.1524 0.1524)
			(layers "F.Cu" "F.Mask" "F.Paste")
			(net "GATE_FAN0_R")
			(options
				(clearance outline)
				(anchor circle)
			)
			(primitives
				(gr_poly
					(pts
						(arc
							(start 0.3048 -0.2032)
							(mid 0.275042 -0.275042)
							(end 0.2032 -0.3048)
						)
						(arc
							(start -0.2032 -0.3048)
							(mid -0.275042 -0.275042)
							(end -0.3048 -0.2032)
						)
						(arc
							(start -0.3048 0.2032)
							(mid -0.275042 0.275042)
							(end -0.2032 0.3048)
						)
						(arc
							(start 0.2032 0.3048)
							(mid 0.275042 0.275042)
							(end 0.3048 0.2032)
						)
					)
					(width 0)
					(fill yes)
				)
			)
		)
		(pad "2" smd custom
			(at 0 0.4445 180)
			(size 0.1524 0.1524)
			(layers "F.Cu" "F.Mask" "F.Paste")
			(net "P12V_IN")
			(options
				(clearance outline)
				(anchor circle)
			)
			(primitives
				(gr_poly
					(pts
						(arc
							(start 0.3048 -0.2032)
							(mid 0.275042 -0.275042)
							(end 0.2032 -0.3048)
						)
						(arc
							(start -0.2032 -0.3048)
							(mid -0.275042 -0.275042)
							(end -0.3048 -0.2032)
						)
						(arc
							(start -0.3048 0.2032)
							(mid -0.275042 0.275042)
							(end -0.2032 0.3048)
						)
						(arc
							(start 0.2032 0.3048)
							(mid 0.275042 0.275042)
							(end 0.3048 0.2032)
						)
					)
					(width 0)
					(fill yes)
				)
			)
		)
	)
)
